# S9S_MB_2U (Grand Teton) — schematic netlist excerpt (pin names and nets, part order shuffled) for the footprints in the layout excerpt that follows; sources: Cadence DE-HDL packaged netlist, KiCad conversion of 03242023_DA0F0TMBIJ0_F0T_Motherboard_J_brd_V01_OCP.brd

PC1352  Q_CAP  0.1UF 25V 10% X7R  pkg 0402  page 272 : A = GND ; B = PVCCIN_CPU0_VREF
R2565  Q_RES  0 5% CHIP  pkg 0402LF  page 231 : A = SMB_FRU_3V3AUX_SCL_R ; B = SMB_FRU_3V3AUX_SCL

(kicad_pcb
	(version 20260206)
	(generator "pcbnew")
	(generator_version "10.0")
	(general
		(thickness 1.6)
		(legacy_teardrops no)
	)
	(paper "A4")
	(title_block
		(title "03242023_DA0F0TMBIJ0_F0T_Motherboard_J_brd_V01_OCP.brd")
		(comment 1 "Grand Teton / footprints 771-772 of 6105")
	)
	(layers
		(0 "F.Cu" signal "TOP")
		(4 "In1.Cu" signal "GND")
		(6 "In2.Cu" signal "IN1")
		(8 "In3.Cu" signal "GND1")
		(10 "In4.Cu" signal "IN2")
		(12 "In5.Cu" signal "GND2")
		(14 "In6.Cu" signal "IN3")
		(16 "In7.Cu" signal "GND3")
		(18 "In8.Cu" signal "VCC")
		(20 "In9.Cu" signal "VCC1")
		(22 "In10.Cu" signal "GND4")
		(24 "In11.Cu" signal "IN4")
		(26 "In12.Cu" signal "GND5")
		(28 "In13.Cu" signal "IN5")
		(30 "In14.Cu" signal "GND6")
		(32 "In15.Cu" signal "IN6")
		(34 "In16.Cu" signal "GND7")
		(2 "B.Cu" signal "BOTTOM")
		(9 "F.Adhes" user "F.Adhesive")
		(11 "B.Adhes" user "B.Adhesive")
		(13 "F.Paste" user "Package Geometry/Pastemask Top")
		(15 "B.Paste" user "Package Geometry/Pastemask Bottom")
		(5 "F.SilkS" user "Ref Des/Silkscreen Top")
		(7 "B.SilkS" user "Ref Des/Silkscreen Bottom")
		(1 "F.Mask" user "Board Geometry/Soldermask Top")
		(3 "B.Mask" user "Board Geometry/Soldermask Bottom")
		(17 "Dwgs.User" user "User.Drawings")
		(19 "Cmts.User" user "User.Comments")
		(21 "Eco1.User" user "User.Eco1")
		(23 "Eco2.User" user "User.Eco2")
		(25 "Edge.Cuts" user "Board Geometry/Outline")
		(27 "Margin" user)
		(31 "F.CrtYd" user "Package Geometry/Place Bound Top")
		(29 "B.CrtYd" user "Package Geometry/Place Bound Bottom")
		(35 "F.Fab" user "Ref Des/Assembly Top")
		(33 "B.Fab" user "Ref Des/Assembly Bottom")
	)
	(footprint ""
		(layer "F.Cu")
		(at 286.033718 -367.357152 -90)
		(property "Reference" "PC1352"
			(at 0 0 270)
			(layer "F.SilkS")
			(hide yes)
			(effects
				(font
					(size 1.27 1.27)
				)
			)
		)
		(property "Value" ""
			(at 0 0 270)
			(layer "F.Fab")
			(effects
				(font
					(size 1.27 1.27)
				)
			)
		)
		(duplicate_pad_numbers_are_jumpers no)
		(fp_line
			(start -0.7874 0.4064)
			(end -0.7874 -0.4064)
			(stroke
				(width 0.1524)
				(type default)
			)
			(layer "F.SilkS")
		)
		(fp_line
			(start 0.7874 0.4064)
			(end -0.7874 0.4064)
			(stroke
				(width 0.1524)
				(type default)
			)
			(layer "F.SilkS")
		)
		(fp_line
			(start -0.7874 -0.4064)
			(end 0.7874 -0.4064)
			(stroke
				(width 0.1524)
				(type default)
			)
			(layer "F.SilkS")
		)
		(fp_line
			(start 0.7874 -0.4064)
			(end 0.7874 0.4064)
			(stroke
				(width 0.1524)
				(type default)
			)
			(layer "F.SilkS")
		)
		(fp_line
			(start -0.67945 0.3048)
			(end -0.67945 -0.305054)
			(stroke
				(width 0.1)
				(type default)
			)
			(layer "F.Fab")
		)
		(fp_line
			(start -0.12065 0.3048)
			(end -0.67945 0.3048)
			(stroke
				(width 0.1)
				(type default)
			)
			(layer "F.Fab")
		)
		(fp_line
			(start 0.120396 0.3048)
			(end 0.120396 0.2794)
			(stroke
				(width 0.1)
				(type default)
			)
			(layer "F.Fab")
		)
		(fp_line
			(start 0.67945 0.3048)
			(end 0.120396 0.3048)
			(stroke
				(width 0.1)
				(type default)
			)
			(layer "F.Fab")
		)
		(fp_line
			(start -0.12065 0.2794)
			(end -0.12065 0.3048)
			(stroke
				(width 0.1)
				(type default)
			)
			(layer "F.Fab")
		)
		(fp_line
			(start 0.120396 0.2794)
			(end -0.12065 0.2794)
			(stroke
				(width 0.1)
				(type default)
			)
			(layer "F.Fab")
		)
		(fp_line
			(start -0.12065 -0.2794)
			(end 0.12065 -0.2794)
			(stroke
				(width 0.1)
				(type default)
			)
			(layer "F.Fab")
		)
		(fp_line
			(start 0.12065 -0.2794)
			(end 0.12065 -0.3048)
			(stroke
				(width 0.1)
				(type default)
			)
			(layer "F.Fab")
		)
		(fp_line
			(start 0.12065 -0.3048)
			(end 0.67945 -0.3048)
			(stroke
				(width 0.1)
				(type default)
			)
			(layer "F.Fab")
		)
		(fp_line
			(start 0.67945 -0.3048)
			(end 0.67945 0.3048)
			(stroke
				(width 0.1)
				(type default)
			)
			(layer "F.Fab")
		)
		(fp_line
			(start -0.67945 -0.305054)
			(end -0.12065 -0.305054)
			(stroke
				(width 0.1)
				(type default)
			)
			(layer "F.Fab")
		)
		(fp_line
			(start -0.12065 -0.305054)
			(end -0.12065 -0.2794)
			(stroke
				(width 0.1)
				(type default)
			)
			(layer "F.Fab")
		)
		(pad "1" smd circle
			(at -0.40005 0 270)
			(size 0 0)
			(layers "F.Cu" "F.Mask" "F.Paste")
			(net "GND")
		)
		(pad "2" smd circle
			(at 0.40005 0 270)
			(size 0 0)
			(layers "F.Cu" "F.Mask" "F.Paste")
			(net "PVCCIN_CPU0_VREF")
		)
	)
	(footprint ""
		(layer "F.Cu")
		(at 128.401572 -132.034026)
		(property "Reference" "R2565"
			(at 0 0 0)
			(layer "F.SilkS")
			(hide yes)
			(effects
				(font
					(size 1.27 1.27)
				)
			)
		)
		(property "Value" ""
			(at 0 0 0)
			(layer "F.Fab")
			(effects
				(font
					(size 1.27 1.27)
				)
			)
		)
		(duplicate_pad_numbers_are_jumpers no)
		(fp_line
			(start -0.7874 -0.4064)
			(end 0.7874 -0.4064)
			(stroke
				(width 0.1524)
				(type default)
			)
			(layer "F.SilkS")
		)
		(fp_line
			(start -0.7874 0.4064)
			(end -0.7874 -0.4064)
			(stroke
				(width 0.1524)
				(type default)
			)
			(layer "F.SilkS")
		)
		(fp_line
			(start 0.7874 -0.4064)
			(end 0.7874 0.4064)
			(stroke
				(width 0.1524)
				(type default)
			)
			(layer "F.SilkS")
		)
		(fp_line
			(start 0.7874 0.4064)
			(end -0.7874 0.4064)
			(stroke
				(width 0.1524)
				(type default)
			)
			(layer "F.SilkS")
		)
		(fp_line
			(start -0.67945 -0.305054)
			(end -0.12065 -0.305054)
			(stroke
				(width 0.1)
				(type default)
			)
			(layer "F.Fab")
		)
		(fp_line
			(start -0.67945 0.3048)
			(end -0.67945 -0.305054)
			(stroke
				(width 0.1)
				(type default)
			)
			(layer "F.Fab")
		)
		(fp_line
			(start -0.12065 -0.305054)
			(end -0.12065 -0.2794)
			(stroke
				(width 0.1)
				(type default)
			)
			(layer "F.Fab")
		)
		(fp_line
			(start -0.12065 -0.2794)
			(end 0.12065 -0.2794)
			(stroke
				(width 0.1)
				(type default)
			)
			(layer "F.Fab")
		)
		(fp_line
			(start -0.12065 0.2794)
			(end -0.12065 0.3048)
			(stroke
				(width 0.1)
				(type default)
			)
			(layer "F.Fab")
		)
		(fp_line
			(start -0.12065 0.3048)
			(end -0.67945 0.3048)
			(stroke
				(width 0.1)
				(type default)
			)
			(layer "F.Fab")
		)
		(fp_line
			(start 0.120396 0.2794)
			(end -0.12065 0.2794)
			(stroke
				(width 0.1)
				(type default)
			)
			(layer "F.Fab")
		)
		(fp_line
			(start 0.120396 0.3048)
			(end 0.120396 0.2794)
			(stroke
				(width 0.1)
				(type default)
			)
			(layer "F.Fab")
		)
		(fp_line
			(start 0.12065 -0.3048)
			(end 0.67945 -0.3048)
			(stroke
				(width 0.1)
				(type default)
			)
			(layer "F.Fab")
		)
		(fp_line
			(start 0.12065 -0.2794)
			(end 0.12065 -0.3048)
			(stroke
				(width 0.1)
				(type default)
			)
			(layer "F.Fab")
		)
		(fp_line
			(start 0.67945 -0.3048)
			(end 0.67945 0.3048)
			(stroke
				(width 0.1)
				(type default)
			)
			(layer "F.Fab")
		)
		(fp_line
			(start 0.67945 0.3048)
			(end 0.120396 0.3048)
			(stroke
				(width 0.1)
				(type default)
			)
			(layer "F.Fab")
		)
		(pad "1" smd circle
			(at -0.40005 0)
			(size 0 0)
			(layers "F.Cu" "F.Mask" "F.Paste")
			(net "SMB_FRU_3V3AUX_SCL_R")
		)
		(pad "2" smd circle
			(at 0.40005 0)
			(size 0 0)
			(layers "F.Cu" "F.Mask" "F.Paste")
			(net "SMB_FRU_3V3AUX_SCL")
		)
	)
)
